# T6G (Grand Teton) — schematic netlist excerpt (pin names and nets, part order shuffled) for the footprints in the layout excerpt that follows; sources: Cadence DE-HDL packaged netlist, KiCad conversion of 04192023_DAF0TMB3IC0_F0TG_MB_C_brd_V02_OCP.brd

C6585  Q_CAP_DIFFBUS  DIFF BUS_0.22UF 6.3V 20% X6S  pkg C0201  page 297 : \1\ = P5E_CPU0_P2_TX_BUF_C_DP<10> ; \2\ = P5E_CPU0_P2_TX_BUF_DP<10>
R6293  Q_RES  4.7K 1% CHIP  pkg 0402LF  page 179 : A = USB_HUB2_TI_GANGED ; B = GND

Q7003  MOSFET_NCH_1D3S  PSMNR58-30YLH EMPTY  pkg SOT1023  page 169
  \1\  = GND
  \2\  = GND
  \3\  = GND
  \4\  = P3V3_AUX_DSC_G2
  \5\  = P3V3_AUX_DSC

(kicad_pcb
	(version 20260206)
	(generator "pcbnew")
	(generator_version "10.0")
	(general
		(thickness 1.6)
		(legacy_teardrops no)
	)
	(paper "A4")
	(title_block
		(title "04192023_DAF0TMB3IC0_F0TG_MB_C_brd_V02_OCP.brd")
		(comment 1 "Grand Teton / footprints 760-762 of 8354")
	)
	(layers
		(0 "F.Cu" signal "TOP")
		(4 "In1.Cu" signal "GND")
		(6 "In2.Cu" signal "IN1")
		(8 "In3.Cu" signal "GND1")
		(10 "In4.Cu" signal "IN2")
		(12 "In5.Cu" signal "GND2")
		(14 "In6.Cu" signal "IN3")
		(16 "In7.Cu" signal "GND3")
		(18 "In8.Cu" signal "VCC")
		(20 "In9.Cu" signal "VCC1")
		(22 "In10.Cu" signal "GND4")
		(24 "In11.Cu" signal "IN4")
		(26 "In12.Cu" signal "GND5")
		(28 "In13.Cu" signal "IN5")
		(30 "In14.Cu" signal "GND6")
		(32 "In15.Cu" signal "IN6")
		(34 "In16.Cu" signal "GND7")
		(2 "B.Cu" signal "BOTTOM")
		(9 "F.Adhes" user "F.Adhesive")
		(11 "B.Adhes" user "B.Adhesive")
		(13 "F.Paste" user "Package Geometry/Pastemask Top")
		(15 "B.Paste" user "Package Geometry/Pastemask Bottom")
		(5 "F.SilkS" user "Ref Des/Silkscreen Top")
		(7 "B.SilkS" user "Ref Des/Silkscreen Bottom")
		(1 "F.Mask" user "Board Geometry/Soldermask Top")
		(3 "B.Mask" user "Board Geometry/Soldermask Bottom")
		(17 "Dwgs.User" user "User.Drawings")
		(19 "Cmts.User" user "User.Comments")
		(21 "Eco1.User" user "User.Eco1")
		(23 "Eco2.User" user "User.Eco2")
		(25 "Edge.Cuts" user "Board Geometry/Outline")
		(27 "Margin" user)
		(31 "F.CrtYd" user "Package Geometry/Place Bound Top")
		(29 "B.CrtYd" user "Package Geometry/Place Bound Bottom")
		(35 "F.Fab" user "Ref Des/Assembly Top")
		(33 "B.Fab" user "Ref Des/Assembly Bottom")
	)
	(footprint ""
		(layer "F.Cu")
		(at 109.219238 -41.17975 90)
		(property "Reference" "R6293"
			(at 0 0 90)
			(layer "F.SilkS")
			(hide yes)
			(effects
				(font
					(size 1.27 1.27)
				)
			)
		)
		(property "Value" ""
			(at 0 0 90)
			(layer "F.Fab")
			(effects
				(font
					(size 1.27 1.27)
				)
			)
		)
		(duplicate_pad_numbers_are_jumpers no)
		(fp_line
			(start 0.7874 -0.4064)
			(end 0.7874 0.4064)
			(stroke
				(width 0.1524)
				(type default)
			)
			(layer "F.SilkS")
		)
		(fp_line
			(start -0.7874 -0.4064)
			(end 0.7874 -0.4064)
			(stroke
				(width 0.1524)
				(type default)
			)
			(layer "F.SilkS")
		)
		(fp_line
			(start 0.7874 0.4064)
			(end -0.7874 0.4064)
			(stroke
				(width 0.1524)
				(type default)
			)
			(layer "F.SilkS")
		)
		(fp_line
			(start -0.7874 0.4064)
			(end -0.7874 -0.4064)
			(stroke
				(width 0.1524)
				(type default)
			)
			(layer "F.SilkS")
		)
		(fp_line
			(start -0.12065 -0.305054)
			(end -0.12065 -0.2794)
			(stroke
				(width 0.1)
				(type default)
			)
			(layer "F.Fab")
		)
		(fp_line
			(start -0.67945 -0.305054)
			(end -0.12065 -0.305054)
			(stroke
				(width 0.1)
				(type default)
			)
			(layer "F.Fab")
		)
		(fp_line
			(start 0.67945 -0.3048)
			(end 0.67945 0.3048)
			(stroke
				(width 0.1)
				(type default)
			)
			(layer "F.Fab")
		)
		(fp_line
			(start 0.12065 -0.3048)
			(end 0.67945 -0.3048)
			(stroke
				(width 0.1)
				(type default)
			)
			(layer "F.Fab")
		)
		(fp_line
			(start 0.12065 -0.2794)
			(end 0.12065 -0.3048)
			(stroke
				(width 0.1)
				(type default)
			)
			(layer "F.Fab")
		)
		(fp_line
			(start -0.12065 -0.2794)
			(end 0.12065 -0.2794)
			(stroke
				(width 0.1)
				(type default)
			)
			(layer "F.Fab")
		)
		(fp_line
			(start 0.120396 0.2794)
			(end -0.12065 0.2794)
			(stroke
				(width 0.1)
				(type default)
			)
			(layer "F.Fab")
		)
		(fp_line
			(start -0.12065 0.2794)
			(end -0.12065 0.3048)
			(stroke
				(width 0.1)
				(type default)
			)
			(layer "F.Fab")
		)
		(fp_line
			(start 0.67945 0.3048)
			(end 0.120396 0.3048)
			(stroke
				(width 0.1)
				(type default)
			)
			(layer "F.Fab")
		)
		(fp_line
			(start 0.120396 0.3048)
			(end 0.120396 0.2794)
			(stroke
				(width 0.1)
				(type default)
			)
			(layer "F.Fab")
		)
		(fp_line
			(start -0.12065 0.3048)
			(end -0.67945 0.3048)
			(stroke
				(width 0.1)
				(type default)
			)
			(layer "F.Fab")
		)
		(fp_line
			(start -0.67945 0.3048)
			(end -0.67945 -0.305054)
			(stroke
				(width 0.1)
				(type default)
			)
			(layer "F.Fab")
		)
		(pad "1" smd circle
			(at -0.40005 0 90)
			(size 0 0)
			(layers "F.Cu" "F.Mask" "F.Paste")
			(net "USB_HUB2_TI_GANGED")
		)
		(pad "2" smd circle
			(at 0.40005 0 90)
			(size 0 0)
			(layers "F.Cu" "F.Mask" "F.Paste")
			(net "GND")
		)
	)
	(footprint ""
		(layer "F.Cu")
		(at 402.415502 -416.899344 -90)
		(property "Reference" "C6585"
			(at 0 0 270)
			(layer "F.SilkS")
			(hide yes)
			(effects
				(font
					(size 1.27 1.27)
				)
			)
		)
		(property "Value" ""
			(at 0 0 270)
			(layer "F.Fab")
			(effects
				(font
					(size 1.27 1.27)
				)
			)
		)
		(duplicate_pad_numbers_are_jumpers no)
		(fp_line
			(start -0.299974 0.150114)
			(end -0.299974 -0.150114)
			(stroke
				(width 0.1)
				(type default)
			)
			(layer "F.Fab")
		)
		(fp_line
			(start 0.299974 0.150114)
			(end -0.299974 0.150114)
			(stroke
				(width 0.1)
				(type default)
			)
			(layer "F.Fab")
		)
		(fp_line
			(start -0.299974 -0.150114)
			(end 0.299974 -0.150114)
			(stroke
				(width 0.1)
				(type default)
			)
			(layer "F.Fab")
		)
		(fp_line
			(start 0.299974 -0.150114)
			(end 0.299974 0.150114)
			(stroke
				(width 0.1)
				(type default)
			)
			(layer "F.Fab")
		)
		(pad "1" smd rect
			(at -0.2667 0 270)
			(size 0.3048 0.381)
			(layers "F.Cu" "F.Mask" "F.Paste")
			(net "P5E_CPU0_P2_TX_BUF_C_DP<10>")
		)
		(pad "2" smd rect
			(at 0.2667 0 270)
			(size 0.3048 0.381)
			(layers "F.Cu" "F.Mask" "F.Paste")
			(net "P5E_CPU0_P2_TX_BUF_DP<10>")
		)
	)
	(footprint ""
		(layer "F.Cu")
		(at 44.2087 -116.10086 90)
		(property "Reference" "Q7003"
			(at -2.4384 -3.292348 90)
			(unlocked yes)
			(layer "F.SilkS")
			(effects
				(font
					(size 0.7874 0.5842)
					(thickness 0.1524)
				)
				(justify left)
			)
		)
		(property "Value" ""
			(at 0 0 90)
			(layer "F.Fab")
			(effects
				(font
					(size 1.27 1.27)
				)
			)
		)
		(duplicate_pad_numbers_are_jumpers no)
		(fp_line
			(start 2.350008 -2.649982)
			(end 2.350008 -2.4892)
			(stroke
				(width 0.1524)
				(type default)
			)
			(layer "F.SilkS")
		)
		(fp_line
			(start -2.350008 -2.649982)
			(end 2.350008 -2.649982)
			(stroke
				(width 0.1524)
				(type default)
			)
			(layer "F.SilkS")
		)
		(fp_line
			(start -2.350008 -2.4384)
			(end -2.350008 -2.649982)
			(stroke
				(width 0.1524)
				(type default)
			)
			(layer "F.SilkS")
		)
		(fp_line
			(start 2.350008 2.4892)
			(end 2.350008 2.649982)
			(stroke
				(width 0.1524)
				(type default)
			)
			(layer "F.SilkS")
		)
		(fp_line
			(start 2.350008 2.649982)
			(end -2.350008 2.649982)
			(stroke
				(width 0.1524)
				(type default)
			)
			(layer "F.SilkS")
		)
		(fp_line
			(start -2.350008 2.649982)
			(end -2.350008 2.413)
			(stroke
				(width 0.1524)
				(type default)
			)
			(layer "F.SilkS")
		)
		(fp_poly
			(pts
				(xy -3.717544 -1.905) (xy -4.758944 -2.3241) (xy -4.758944 -1.524)
			)
			(stroke
				(width 0)
				(type default)
			)
			(fill yes)
			(layer "F.SilkS")
		)
		(fp_line
			(start 2.350008 -2.649982)
			(end 2.350008 2.649982)
			(stroke
				(width 0.1)
				(type default)
			)
			(layer "F.Fab")
		)
		(fp_line
			(start -2.350008 -2.649982)
			(end 2.350008 -2.649982)
			(stroke
				(width 0.1)
				(type default)
			)
			(layer "F.Fab")
		)
		(fp_line
			(start 2.350008 2.649982)
			(end -2.350008 2.649982)
			(stroke
				(width 0.1)
				(type default)
			)
			(layer "F.Fab")
		)
		(fp_line
			(start -2.350008 2.649982)
			(end -2.350008 -2.649982)
			(stroke
				(width 0.1)
				(type default)
			)
			(layer "F.Fab")
		)
		(fp_poly
			(pts
				(xy -3.717544 -1.905) (xy -4.758944 -2.3241) (xy -4.758944 -1.524)
			)
			(stroke
				(width 0)
				(type default)
			)
			(fill yes)
			(layer "F.Fab")
		)
		(pad "1" smd rect
			(at -2.999994 -1.905)
			(size 0.7112 1.1684)
			(layers "F.Cu" "F.Mask" "F.Paste")
			(net "GND")
		)
		(pad "2" smd rect
			(at -2.999994 -0.635)
			(size 0.7112 1.1684)
			(layers "F.Cu" "F.Mask" "F.Paste")
			(net "GND")
		)
		(pad "3" smd rect
			(at -2.999994 0.635)
			(size 0.7112 1.1684)
			(layers "F.Cu" "F.Mask" "F.Paste")
			(net "GND")
		)
		(pad "4" smd rect
			(at -2.999994 1.905)
			(size 0.7112 1.1684)
			(layers "F.Cu" "F.Mask" "F.Paste")
			(net "P3V3_AUX_DSC_G2")
		)
		(pad "5" smd circle
			(at 0.925068 0)
			(size 0 0)
			(layers "F.Cu" "F.Mask" "F.Paste")
			(net "P3V3_AUX_DSC")
		)
		(zone
			(layer "F.Cu")
			(hatch none 0.5)
			(connect_pads
				(clearance 0)
			)
			(min_thickness 0.25)
			(keepout
				(tracks not_allowed)
				(vias allowed)
				(pads allowed)
				(copperpour not_allowed)
				(footprints allowed)
			)
			(placement
				(enabled no)
				(sheetname "")
			)
			(fill
				(thermal_gap 0.5)
				(thermal_bridge_width 0.5)
				(island_removal_mode 0)
			)
			(polygon
				(pts
					(xy 41.5671 -118.43766) (xy 41.7957 -118.43766) (xy 41.7957 -117.75186) (xy 42.0497 -117.75186)
					(xy 42.0497 -114.65306) (xy 46.3677 -114.65306) (xy 46.3677 -117.75186) (xy 46.6217 -117.75186)
					(xy 46.6217 -118.43766) (xy 46.8503 -118.43766) (xy 46.8503 -113.75136) (xy 41.5671 -113.75136)
				)
			)
		)
	)
)
